# T6G (Grand Teton) — schematic netlist excerpt (pin names and nets, part order shuffled) for the footprints in the layout excerpt that follows; sources: Cadence DE-HDL packaged netlist, KiCad conversion of 04192023_DAF0TMB3IC0_F0TG_MB_C_brd_V02_OCP.brd

C1276  Q_CAP  22UF 16V 20% X6S  pkg C0805  page 145 : A = P12V_E1S_0_R ; B = GND
R4211  Q_RES  200K 1% CHIP  pkg 0402LF  page 235 : A = P3V3_AUX ; B = FM_THERMAL_ALERT_N
PL39  Q_INDUCTOR  120NH/69A IND  pkg SMLF  page 220 : \1\ = IND_CPU1_P1_CPL0 ; \2\ = GND

(kicad_pcb
	(version 20260206)
	(generator "pcbnew")
	(generator_version "10.0")
	(general
		(thickness 1.6)
		(legacy_teardrops no)
	)
	(paper "A4")
	(title_block
		(title "04192023_DAF0TMB3IC0_F0TG_MB_C_brd_V02_OCP.brd")
		(comment 1 "Grand Teton / footprints 2404-2406 of 8354")
	)
	(layers
		(0 "F.Cu" signal "TOP")
		(4 "In1.Cu" signal "GND")
		(6 "In2.Cu" signal "IN1")
		(8 "In3.Cu" signal "GND1")
		(10 "In4.Cu" signal "IN2")
		(12 "In5.Cu" signal "GND2")
		(14 "In6.Cu" signal "IN3")
		(16 "In7.Cu" signal "GND3")
		(18 "In8.Cu" signal "VCC")
		(20 "In9.Cu" signal "VCC1")
		(22 "In10.Cu" signal "GND4")
		(24 "In11.Cu" signal "IN4")
		(26 "In12.Cu" signal "GND5")
		(28 "In13.Cu" signal "IN5")
		(30 "In14.Cu" signal "GND6")
		(32 "In15.Cu" signal "IN6")
		(34 "In16.Cu" signal "GND7")
		(2 "B.Cu" signal "BOTTOM")
		(9 "F.Adhes" user "F.Adhesive")
		(11 "B.Adhes" user "B.Adhesive")
		(13 "F.Paste" user "Package Geometry/Pastemask Top")
		(15 "B.Paste" user "Package Geometry/Pastemask Bottom")
		(5 "F.SilkS" user "Ref Des/Silkscreen Top")
		(7 "B.SilkS" user "Ref Des/Silkscreen Bottom")
		(1 "F.Mask" user "Board Geometry/Soldermask Top")
		(3 "B.Mask" user "Board Geometry/Soldermask Bottom")
		(17 "Dwgs.User" user "User.Drawings")
		(19 "Cmts.User" user "User.Comments")
		(21 "Eco1.User" user "User.Eco1")
		(23 "Eco2.User" user "User.Eco2")
		(25 "Edge.Cuts" user "Board Geometry/Outline")
		(27 "Margin" user)
		(31 "F.CrtYd" user "Package Geometry/Place Bound Top")
		(29 "B.CrtYd" user "Package Geometry/Place Bound Bottom")
		(35 "F.Fab" user "Ref Des/Assembly Top")
		(33 "B.Fab" user "Ref Des/Assembly Bottom")
	)
	(footprint ""
		(layer "F.Cu")
		(at 368.427 -411.226 90)
		(property "Reference" "R4211"
			(at 0 0 90)
			(layer "F.SilkS")
			(hide yes)
			(effects
				(font
					(size 1.27 1.27)
				)
			)
		)
		(property "Value" ""
			(at 0 0 90)
			(layer "F.Fab")
			(effects
				(font
					(size 1.27 1.27)
				)
			)
		)
		(duplicate_pad_numbers_are_jumpers no)
		(fp_line
			(start 0.7874 -0.4064)
			(end 0.7874 0.4064)
			(stroke
				(width 0.1524)
				(type default)
			)
			(layer "F.SilkS")
		)
		(fp_line
			(start -0.7874 -0.4064)
			(end 0.7874 -0.4064)
			(stroke
				(width 0.1524)
				(type default)
			)
			(layer "F.SilkS")
		)
		(fp_line
			(start 0.7874 0.4064)
			(end -0.7874 0.4064)
			(stroke
				(width 0.1524)
				(type default)
			)
			(layer "F.SilkS")
		)
		(fp_line
			(start -0.7874 0.4064)
			(end -0.7874 -0.4064)
			(stroke
				(width 0.1524)
				(type default)
			)
			(layer "F.SilkS")
		)
		(fp_line
			(start -0.12065 -0.305054)
			(end -0.12065 -0.2794)
			(stroke
				(width 0.1)
				(type default)
			)
			(layer "F.Fab")
		)
		(fp_line
			(start -0.67945 -0.305054)
			(end -0.12065 -0.305054)
			(stroke
				(width 0.1)
				(type default)
			)
			(layer "F.Fab")
		)
		(fp_line
			(start 0.67945 -0.3048)
			(end 0.67945 0.3048)
			(stroke
				(width 0.1)
				(type default)
			)
			(layer "F.Fab")
		)
		(fp_line
			(start 0.12065 -0.3048)
			(end 0.67945 -0.3048)
			(stroke
				(width 0.1)
				(type default)
			)
			(layer "F.Fab")
		)
		(fp_line
			(start 0.12065 -0.2794)
			(end 0.12065 -0.3048)
			(stroke
				(width 0.1)
				(type default)
			)
			(layer "F.Fab")
		)
		(fp_line
			(start -0.12065 -0.2794)
			(end 0.12065 -0.2794)
			(stroke
				(width 0.1)
				(type default)
			)
			(layer "F.Fab")
		)
		(fp_line
			(start 0.120396 0.2794)
			(end -0.12065 0.2794)
			(stroke
				(width 0.1)
				(type default)
			)
			(layer "F.Fab")
		)
		(fp_line
			(start -0.12065 0.2794)
			(end -0.12065 0.3048)
			(stroke
				(width 0.1)
				(type default)
			)
			(layer "F.Fab")
		)
		(fp_line
			(start 0.67945 0.3048)
			(end 0.120396 0.3048)
			(stroke
				(width 0.1)
				(type default)
			)
			(layer "F.Fab")
		)
		(fp_line
			(start 0.120396 0.3048)
			(end 0.120396 0.2794)
			(stroke
				(width 0.1)
				(type default)
			)
			(layer "F.Fab")
		)
		(fp_line
			(start -0.12065 0.3048)
			(end -0.67945 0.3048)
			(stroke
				(width 0.1)
				(type default)
			)
			(layer "F.Fab")
		)
		(fp_line
			(start -0.67945 0.3048)
			(end -0.67945 -0.305054)
			(stroke
				(width 0.1)
				(type default)
			)
			(layer "F.Fab")
		)
		(pad "1" smd circle
			(at -0.40005 0 90)
			(size 0 0)
			(layers "F.Cu" "F.Mask" "F.Paste")
			(net "P3V3_AUX")
		)
		(pad "2" smd circle
			(at 0.40005 0 90)
			(size 0 0)
			(layers "F.Cu" "F.Mask" "F.Paste")
			(net "FM_THERMAL_ALERT_N")
		)
	)
	(footprint ""
		(layer "F.Cu")
		(at 111.4298 -332.733142 90)
		(property "Reference" "PL39"
			(at -3.302 4.022852 90)
			(unlocked yes)
			(layer "F.SilkS")
			(effects
				(font
					(size 0.7874 0.5842)
					(thickness 0.1524)
				)
				(justify left)
			)
		)
		(property "Value" ""
			(at 0 0 90)
			(layer "F.Fab")
			(effects
				(font
					(size 1.27 1.27)
				)
			)
		)
		(duplicate_pad_numbers_are_jumpers no)
		(fp_line
			(start 3.24993 -3.24993)
			(end 3.24993 -2.2352)
			(stroke
				(width 0.1524)
				(type default)
			)
			(layer "F.SilkS")
		)
		(fp_line
			(start -3.24993 -3.24993)
			(end 3.24993 -3.24993)
			(stroke
				(width 0.1524)
				(type default)
			)
			(layer "F.SilkS")
		)
		(fp_line
			(start -3.24993 -2.2352)
			(end -3.24993 -3.24993)
			(stroke
				(width 0.1524)
				(type default)
			)
			(layer "F.SilkS")
		)
		(fp_line
			(start 3.24993 2.2352)
			(end 3.24993 3.24993)
			(stroke
				(width 0.1524)
				(type default)
			)
			(layer "F.SilkS")
		)
		(fp_line
			(start 3.24993 3.24993)
			(end -3.24993 3.24993)
			(stroke
				(width 0.1524)
				(type default)
			)
			(layer "F.SilkS")
		)
		(fp_line
			(start -3.24993 3.24993)
			(end -3.24993 2.2352)
			(stroke
				(width 0.1524)
				(type default)
			)
			(layer "F.SilkS")
		)
		(fp_line
			(start 3.24993 -3.24993)
			(end 3.24993 3.24993)
			(stroke
				(width 0.1)
				(type default)
			)
			(layer "F.Fab")
		)
		(fp_line
			(start -3.24993 -3.24993)
			(end 3.24993 -3.24993)
			(stroke
				(width 0.1)
				(type default)
			)
			(layer "F.Fab")
		)
		(fp_line
			(start 3.24993 3.24993)
			(end -3.24993 3.24993)
			(stroke
				(width 0.1)
				(type default)
			)
			(layer "F.Fab")
		)
		(fp_line
			(start -3.24993 3.24993)
			(end -3.24993 -3.24993)
			(stroke
				(width 0.1)
				(type default)
			)
			(layer "F.Fab")
		)
		(pad "1" smd rect
			(at -2.29997 0 90)
			(size 2.0066 4.2164)
			(layers "F.Cu" "F.Mask" "F.Paste")
			(net "IND_CPU1_P1_CPL0")
		)
		(pad "2" smd rect
			(at 2.29997 0 90)
			(size 2.0066 4.2164)
			(layers "F.Cu" "F.Mask" "F.Paste")
			(net "GND")
		)
	)
	(footprint ""
		(layer "F.Cu")
		(at 243.446808 -42.063162 -90)
		(property "Reference" "C1276"
			(at 0 0 270)
			(layer "F.SilkS")
			(hide yes)
			(effects
				(font
					(size 1.27 1.27)
				)
			)
		)
		(property "Value" ""
			(at 0 0 270)
			(layer "F.Fab")
			(effects
				(font
					(size 1.27 1.27)
				)
			)
		)
		(duplicate_pad_numbers_are_jumpers no)
		(fp_line
			(start -1.524 0.762)
			(end -1.524 -0.762)
			(stroke
				(width 0.1524)
				(type default)
			)
			(layer "F.SilkS")
		)
		(fp_line
			(start 1.524 0.762)
			(end -1.524 0.762)
			(stroke
				(width 0.1524)
				(type default)
			)
			(layer "F.SilkS")
		)
		(fp_line
			(start -1.524 -0.762)
			(end 1.524 -0.762)
			(stroke
				(width 0.1524)
				(type default)
			)
			(layer "F.SilkS")
		)
		(fp_line
			(start 1.524 -0.762)
			(end 1.524 0.762)
			(stroke
				(width 0.1524)
				(type default)
			)
			(layer "F.SilkS")
		)
		(fp_line
			(start -1.1049 0.724916)
			(end 1.1049 0.724916)
			(stroke
				(width 0.1)
				(type default)
			)
			(layer "F.Fab")
		)
		(fp_line
			(start 1.1049 0.724916)
			(end 1.1049 -0.724916)
			(stroke
				(width 0.1)
				(type default)
			)
			(layer "F.Fab")
		)
		(fp_line
			(start -1.1049 -0.724916)
			(end -1.1049 0.724916)
			(stroke
				(width 0.1)
				(type default)
			)
			(layer "F.Fab")
		)
		(fp_line
			(start 1.1049 -0.724916)
			(end -1.1049 -0.724916)
			(stroke
				(width 0.1)
				(type default)
			)
			(layer "F.Fab")
		)
		(pad "1" smd rect
			(at -0.889 0 90)
			(size 1.016 1.27)
			(layers "F.Cu" "F.Mask" "F.Paste")
			(net "P12V_E1S_0_R")
		)
		(pad "2" smd rect
			(at 0.889 0 90)
			(size 1.016 1.27)
			(layers "F.Cu" "F.Mask" "F.Paste")
			(net "GND")
		)
	)
)
